# S9S_MB_2U (Grand Teton) — schematic netlist excerpt (pin names and nets, part order shuffled) for the footprints in the layout excerpt that follows; sources: Cadence DE-HDL packaged netlist, KiCad conversion of 03242023_DA0F0TMBIJ0_F0T_Motherboard_J_brd_V01_OCP.brd

R1354  Q_RES  100K 1% CHIP  pkg 0402LF  page 154 : A = RMII_BMC_OCP_TXD_0 ; B = GND

DB7  TDR_3P  EMPTY  pkg TH2  page 309
  GND  = T1_GND
  IO1  = TDR_SE_50_OHM_TOP
  IO2  = TDR_SE_50_OHM_TOP

R4515  Q_RES  100K 1% CHIP  pkg 0402LF  page 151 : A = P3V3_AUX ; B = UART_BMC_BIC_RX

(kicad_pcb
	(version 20260206)
	(generator "pcbnew")
	(generator_version "10.0")
	(general
		(thickness 1.6)
		(legacy_teardrops no)
	)
	(paper "A4")
	(title_block
		(title "03242023_DA0F0TMBIJ0_F0T_Motherboard_J_brd_V01_OCP.brd")
		(comment 1 "Grand Teton / footprints 3978-3980 of 6105")
	)
	(layers
		(0 "F.Cu" signal "TOP")
		(4 "In1.Cu" signal "GND")
		(6 "In2.Cu" signal "IN1")
		(8 "In3.Cu" signal "GND1")
		(10 "In4.Cu" signal "IN2")
		(12 "In5.Cu" signal "GND2")
		(14 "In6.Cu" signal "IN3")
		(16 "In7.Cu" signal "GND3")
		(18 "In8.Cu" signal "VCC")
		(20 "In9.Cu" signal "VCC1")
		(22 "In10.Cu" signal "GND4")
		(24 "In11.Cu" signal "IN4")
		(26 "In12.Cu" signal "GND5")
		(28 "In13.Cu" signal "IN5")
		(30 "In14.Cu" signal "GND6")
		(32 "In15.Cu" signal "IN6")
		(34 "In16.Cu" signal "GND7")
		(2 "B.Cu" signal "BOTTOM")
		(9 "F.Adhes" user "F.Adhesive")
		(11 "B.Adhes" user "B.Adhesive")
		(13 "F.Paste" user "Package Geometry/Pastemask Top")
		(15 "B.Paste" user "Package Geometry/Pastemask Bottom")
		(5 "F.SilkS" user "Ref Des/Silkscreen Top")
		(7 "B.SilkS" user "Ref Des/Silkscreen Bottom")
		(1 "F.Mask" user "Board Geometry/Soldermask Top")
		(3 "B.Mask" user "Board Geometry/Soldermask Bottom")
		(17 "Dwgs.User" user "User.Drawings")
		(19 "Cmts.User" user "User.Comments")
		(21 "Eco1.User" user "User.Eco1")
		(23 "Eco2.User" user "User.Eco2")
		(25 "Edge.Cuts" user "Board Geometry/Outline")
		(27 "Margin" user)
		(31 "F.CrtYd" user "Package Geometry/Place Bound Top")
		(29 "B.CrtYd" user "Package Geometry/Place Bound Bottom")
		(35 "F.Fab" user "Ref Des/Assembly Top")
		(33 "B.Fab" user "Ref Des/Assembly Bottom")
	)
	(footprint ""
		(layer "F.Cu")
		(at 211.99729 -71.13143)
		(property "Reference" "R1354"
			(at 0 0 0)
			(layer "F.SilkS")
			(hide yes)
			(effects
				(font
					(size 1.27 1.27)
				)
			)
		)
		(property "Value" ""
			(at 0 0 0)
			(layer "F.Fab")
			(effects
				(font
					(size 1.27 1.27)
				)
			)
		)
		(duplicate_pad_numbers_are_jumpers no)
		(fp_line
			(start -0.7874 -0.4064)
			(end 0.7874 -0.4064)
			(stroke
				(width 0.1524)
				(type default)
			)
			(layer "F.SilkS")
		)
		(fp_line
			(start -0.7874 0.4064)
			(end -0.7874 -0.4064)
			(stroke
				(width 0.1524)
				(type default)
			)
			(layer "F.SilkS")
		)
		(fp_line
			(start 0.7874 -0.4064)
			(end 0.7874 0.4064)
			(stroke
				(width 0.1524)
				(type default)
			)
			(layer "F.SilkS")
		)
		(fp_line
			(start 0.7874 0.4064)
			(end -0.7874 0.4064)
			(stroke
				(width 0.1524)
				(type default)
			)
			(layer "F.SilkS")
		)
		(fp_line
			(start -0.67945 -0.305054)
			(end -0.12065 -0.305054)
			(stroke
				(width 0.1)
				(type default)
			)
			(layer "F.Fab")
		)
		(fp_line
			(start -0.67945 0.3048)
			(end -0.67945 -0.305054)
			(stroke
				(width 0.1)
				(type default)
			)
			(layer "F.Fab")
		)
		(fp_line
			(start -0.12065 -0.305054)
			(end -0.12065 -0.2794)
			(stroke
				(width 0.1)
				(type default)
			)
			(layer "F.Fab")
		)
		(fp_line
			(start -0.12065 -0.2794)
			(end 0.12065 -0.2794)
			(stroke
				(width 0.1)
				(type default)
			)
			(layer "F.Fab")
		)
		(fp_line
			(start -0.12065 0.2794)
			(end -0.12065 0.3048)
			(stroke
				(width 0.1)
				(type default)
			)
			(layer "F.Fab")
		)
		(fp_line
			(start -0.12065 0.3048)
			(end -0.67945 0.3048)
			(stroke
				(width 0.1)
				(type default)
			)
			(layer "F.Fab")
		)
		(fp_line
			(start 0.120396 0.2794)
			(end -0.12065 0.2794)
			(stroke
				(width 0.1)
				(type default)
			)
			(layer "F.Fab")
		)
		(fp_line
			(start 0.120396 0.3048)
			(end 0.120396 0.2794)
			(stroke
				(width 0.1)
				(type default)
			)
			(layer "F.Fab")
		)
		(fp_line
			(start 0.12065 -0.3048)
			(end 0.67945 -0.3048)
			(stroke
				(width 0.1)
				(type default)
			)
			(layer "F.Fab")
		)
		(fp_line
			(start 0.12065 -0.2794)
			(end 0.12065 -0.3048)
			(stroke
				(width 0.1)
				(type default)
			)
			(layer "F.Fab")
		)
		(fp_line
			(start 0.67945 -0.3048)
			(end 0.67945 0.3048)
			(stroke
				(width 0.1)
				(type default)
			)
			(layer "F.Fab")
		)
		(fp_line
			(start 0.67945 0.3048)
			(end 0.120396 0.3048)
			(stroke
				(width 0.1)
				(type default)
			)
			(layer "F.Fab")
		)
		(pad "1" smd circle
			(at -0.40005 0)
			(size 0 0)
			(layers "F.Cu" "F.Mask" "F.Paste")
			(net "RMII_BMC_OCP_TXD_0")
		)
		(pad "2" smd circle
			(at 0.40005 0)
			(size 0 0)
			(layers "F.Cu" "F.Mask" "F.Paste")
			(net "GND")
		)
	)
	(footprint ""
		(layer "F.Cu")
		(at 374.03151 -413.918908 90)
		(property "Reference" "R4515"
			(at 0 0 90)
			(layer "F.SilkS")
			(hide yes)
			(effects
				(font
					(size 1.27 1.27)
				)
			)
		)
		(property "Value" ""
			(at 0 0 90)
			(layer "F.Fab")
			(effects
				(font
					(size 1.27 1.27)
				)
			)
		)
		(duplicate_pad_numbers_are_jumpers no)
		(fp_line
			(start 0.7874 -0.4064)
			(end 0.7874 0.4064)
			(stroke
				(width 0.1524)
				(type default)
			)
			(layer "F.SilkS")
		)
		(fp_line
			(start -0.7874 -0.4064)
			(end 0.7874 -0.4064)
			(stroke
				(width 0.1524)
				(type default)
			)
			(layer "F.SilkS")
		)
		(fp_line
			(start 0.7874 0.4064)
			(end -0.7874 0.4064)
			(stroke
				(width 0.1524)
				(type default)
			)
			(layer "F.SilkS")
		)
		(fp_line
			(start -0.7874 0.4064)
			(end -0.7874 -0.4064)
			(stroke
				(width 0.1524)
				(type default)
			)
			(layer "F.SilkS")
		)
		(fp_line
			(start -0.12065 -0.305054)
			(end -0.12065 -0.2794)
			(stroke
				(width 0.1)
				(type default)
			)
			(layer "F.Fab")
		)
		(fp_line
			(start -0.67945 -0.305054)
			(end -0.12065 -0.305054)
			(stroke
				(width 0.1)
				(type default)
			)
			(layer "F.Fab")
		)
		(fp_line
			(start 0.67945 -0.3048)
			(end 0.67945 0.3048)
			(stroke
				(width 0.1)
				(type default)
			)
			(layer "F.Fab")
		)
		(fp_line
			(start 0.12065 -0.3048)
			(end 0.67945 -0.3048)
			(stroke
				(width 0.1)
				(type default)
			)
			(layer "F.Fab")
		)
		(fp_line
			(start 0.12065 -0.2794)
			(end 0.12065 -0.3048)
			(stroke
				(width 0.1)
				(type default)
			)
			(layer "F.Fab")
		)
		(fp_line
			(start -0.12065 -0.2794)
			(end 0.12065 -0.2794)
			(stroke
				(width 0.1)
				(type default)
			)
			(layer "F.Fab")
		)
		(fp_line
			(start 0.120396 0.2794)
			(end -0.12065 0.2794)
			(stroke
				(width 0.1)
				(type default)
			)
			(layer "F.Fab")
		)
		(fp_line
			(start -0.12065 0.2794)
			(end -0.12065 0.3048)
			(stroke
				(width 0.1)
				(type default)
			)
			(layer "F.Fab")
		)
		(fp_line
			(start 0.67945 0.3048)
			(end 0.120396 0.3048)
			(stroke
				(width 0.1)
				(type default)
			)
			(layer "F.Fab")
		)
		(fp_line
			(start 0.120396 0.3048)
			(end 0.120396 0.2794)
			(stroke
				(width 0.1)
				(type default)
			)
			(layer "F.Fab")
		)
		(fp_line
			(start -0.12065 0.3048)
			(end -0.67945 0.3048)
			(stroke
				(width 0.1)
				(type default)
			)
			(layer "F.Fab")
		)
		(fp_line
			(start -0.67945 0.3048)
			(end -0.67945 -0.305054)
			(stroke
				(width 0.1)
				(type default)
			)
			(layer "F.Fab")
		)
		(pad "1" smd circle
			(at -0.40005 0 90)
			(size 0 0)
			(layers "F.Cu" "F.Mask" "F.Paste")
			(net "P3V3_AUX")
		)
		(pad "2" smd circle
			(at 0.40005 0 90)
			(size 0 0)
			(layers "F.Cu" "F.Mask" "F.Paste")
			(net "UART_BMC_BIC_RX")
		)
	)
	(footprint ""
		(layer "F.Cu")
		(at 483.281228 -343.22893)
		(property "Reference" "DB7"
			(at 2.576068 2.020062 90)
			(unlocked yes)
			(layer "F.SilkS")
			(effects
				(font
					(size 0.7874 0.5842)
					(thickness 0.1524)
				)
				(justify left)
			)
		)
		(property "Value" ""
			(at 0 0 0)
			(layer "F.Fab")
			(effects
				(font
					(size 1.27 1.27)
				)
			)
		)
		(duplicate_pad_numbers_are_jumpers no)
		(fp_line
			(start -3.330702 -4.771136)
			(end 3.330702 -4.771136)
			(stroke
				(width 0.1524)
				(type default)
			)
			(layer "F.SilkS")
		)
		(fp_line
			(start 0 4.011168)
			(end -3.330702 -4.771136)
			(stroke
				(width 0.1524)
				(type default)
			)
			(layer "F.SilkS")
		)
		(fp_line
			(start 3.330702 -4.771136)
			(end 0 4.011168)
			(stroke
				(width 0.1524)
				(type default)
			)
			(layer "F.SilkS")
		)
		(fp_line
			(start -3.330702 -4.771136)
			(end 3.330702 -4.771136)
			(stroke
				(width 0.1)
				(type default)
			)
			(layer "F.Fab")
		)
		(fp_line
			(start 0 4.011168)
			(end -3.330702 -4.771136)
			(stroke
				(width 0.1)
				(type default)
			)
			(layer "F.Fab")
		)
		(fp_line
			(start 3.330702 -4.771136)
			(end 0 4.011168)
			(stroke
				(width 0.1)
				(type default)
			)
			(layer "F.Fab")
		)
		(pad "1" thru_hole circle
			(at 0 0)
			(size 2.159 2.159)
			(drill 1.7018)
			(layers "*.Cu" "*.Mask")
			(remove_unused_layers no)
			(net "T1_GND")
			(clearance 0.0254)
			(thermal_gap 0.0254)
		)
		(pad "2" thru_hole circle
			(at -1.27 -3.348736)
			(size 2.159 2.159)
			(drill 1.7018)
			(layers "*.Cu" "*.Mask")
			(remove_unused_layers no)
			(net "TDR_SE_50_OHM_TOP")
			(clearance 0.0254)
			(thermal_gap 0.0254)
		)
		(pad "3" thru_hole circle
			(at 1.27 -3.348736)
			(size 2.159 2.159)
			(drill 1.7018)
			(layers "*.Cu" "*.Mask")
			(remove_unused_layers no)
			(net "TDR_SE_50_OHM_TOP")
			(clearance 0.0254)
			(thermal_gap 0.0254)
		)
	)
)
